(kicad_pcb
	(version 20260206)
	(generator "pcbnew")
	(generator_version "10.0")
	(general
		(thickness 1.6)
		(legacy_teardrops no)
	)
	(paper "A4")
	(title_block
		(title "Bryce Canyon_F.DPB_16315-1-OCP.brd")
		(comment 1 "Bryce Canyon / footprints 759-765 of 2223")
	)
	(layers
		(0 "F.Cu" signal "TOP")
		(4 "In1.Cu" signal "L2GND")
		(6 "In2.Cu" signal "L3")
		(8 "In3.Cu" signal "L4GND")
		(10 "In4.Cu" signal "L5")
		(12 "In5.Cu" signal "L6VCC")
		(14 "In6.Cu" signal "L7VCC")
		(16 "In7.Cu" signal "L8")
		(18 "In8.Cu" signal "L9GND")
		(20 "In9.Cu" signal "L10")
		(22 "In10.Cu" signal "L11GND")
		(2 "B.Cu" signal "BOTTOM")
		(9 "F.Adhes" user "F.Adhesive")
		(11 "B.Adhes" user "B.Adhesive")
		(13 "F.Paste" user "Package Geometry/Pastemask Top")
		(15 "B.Paste" user "Package Geometry/Pastemask Bottom")
		(5 "F.SilkS" user "Ref Des/Silkscreen Top")
		(7 "B.SilkS" user "Ref Des/Silkscreen Bottom")
		(1 "F.Mask" user "Board Geometry/Soldermask Top")
		(3 "B.Mask" user "Board Geometry/Soldermask Bottom")
		(17 "Dwgs.User" user "User.Drawings")
		(19 "Cmts.User" user "User.Comments")
		(21 "Eco1.User" user "User.Eco1")
		(23 "Eco2.User" user "User.Eco2")
		(25 "Edge.Cuts" user "Board Geometry/Outline")
		(27 "Margin" user)
		(31 "F.CrtYd" user "Package Geometry/Place Bound Top")
		(29 "B.CrtYd" user "Package Geometry/Place Bound Bottom")
		(35 "F.Fab" user "Ref Des/Assembly Top")
		(33 "B.Fab" user "Ref Des/Assembly Bottom")
	)
	(footprint ""
		(layer "F.Cu")
		(at 268.816582 15.772638)
		(property "Reference" "U35"
			(at 0 0 0)
			(layer "F.SilkS")
			(hide yes)
			(effects
				(font
					(size 1.27 1.27)
				)
			)
		)
		(property "Value" "TPS2065DBVT-GP"
			(at 0 -5.1308 0)
			(unlocked yes)
			(layer "F.Fab")
			(hide yes)
			(effects
				(font
					(size 1.016 1.016)
					(thickness 0.1524)
				)
			)
		)
		(property "Device Type" "SOT-23-5H58"
			(at 0 -6.7564 0)
			(unlocked yes)
			(layer "F.Fab")
			(hide yes)
			(effects
				(font
					(size 1.016 1.016)
					(thickness 0.1524)
				)
			)
		)
		(duplicate_pad_numbers_are_jumpers no)
		(fp_line
			(start -1.778 -2.286)
			(end -1.778 2.286)
			(stroke
				(width 0.1524)
				(type default)
			)
			(layer "F.SilkS")
		)
		(fp_line
			(start -1.778 2.286)
			(end -0.254 2.286)
			(stroke
				(width 0.1524)
				(type default)
			)
			(layer "F.SilkS")
		)
		(fp_line
			(start -1.778 2.286)
			(end 1.778 2.286)
			(stroke
				(width 0.1524)
				(type default)
			)
			(layer "F.SilkS")
		)
		(fp_line
			(start -1.7272 2.2352)
			(end -1.7272 0.762)
			(stroke
				(width 0.3302)
				(type default)
			)
			(layer "F.SilkS")
		)
		(fp_line
			(start -0.7112 2.2352)
			(end -1.7272 2.2352)
			(stroke
				(width 0.3302)
				(type default)
			)
			(layer "F.SilkS")
		)
		(fp_line
			(start -0.254 2.286)
			(end 1.778 2.286)
			(stroke
				(width 0.1524)
				(type default)
			)
			(layer "F.SilkS")
		)
		(fp_line
			(start 1.778 -2.286)
			(end -1.778 -2.286)
			(stroke
				(width 0.1524)
				(type default)
			)
			(layer "F.SilkS")
		)
		(fp_line
			(start 1.778 2.286)
			(end 1.778 -2.286)
			(stroke
				(width 0.1524)
				(type default)
			)
			(layer "F.SilkS")
		)
		(fp_poly
			(pts
				(xy -0.9652 2.4384) (xy -1.3208 2.794) (xy -0.6096 2.794)
			)
			(stroke
				(width 0)
				(type default)
			)
			(fill yes)
			(layer "F.SilkS")
		)
		(fp_rect
			(start -1.778 2.286)
			(end 1.778 -2.286)
			(stroke
				(width 0)
				(type default)
			)
			(fill no)
			(layer "F.CrtYd")
		)
		(fp_rect
			(start -1.778 2.286)
			(end 1.778 -2.286)
			(stroke
				(width 0)
				(type default)
			)
			(fill no)
			(layer "F.Fab")
		)
		(pad "1" smd rect
			(at -0.94996 1.143)
			(size 0.508 1.524)
			(layers "F.Cu" "F.Mask" "F.Paste")
			(net "P5V_USB_B")
		)
		(pad "2" smd rect
			(at 0 1.143)
			(size 0.508 1.524)
			(layers "F.Cu" "F.Mask" "F.Paste")
			(net "GND")
		)
		(pad "3" smd rect
			(at 0.94996 1.143)
			(size 0.508 1.524)
			(layers "F.Cu" "F.Mask" "F.Paste")
			(net "USB_OCS_N2")
		)
		(pad "4" smd rect
			(at 0.94996 -1.143)
			(size 0.508 1.524)
			(layers "F.Cu" "F.Mask" "F.Paste")
			(net "USB_EN_2")
		)
		(pad "5" smd rect
			(at -0.94996 -1.143)
			(size 0.508 1.524)
			(layers "F.Cu" "F.Mask" "F.Paste")
			(net "P5V_B")
		)
	)
	(footprint ""
		(layer "F.Cu")
		(at 319.9892 -273.940016 90)
		(property "Reference" "VIA1"
			(at 0 0 90)
			(layer "F.SilkS")
			(hide yes)
			(effects
				(font
					(size 1.27 1.27)
				)
			)
		)
		(property "Value" "100OHM-8L-1D6MM-L18L16-GP"
			(at -3.7211 -4.5085 90)
			(unlocked yes)
			(layer "F.Fab")
			(hide yes)
			(effects
				(font
					(size 1.016 1.016)
					(thickness 0.1524)
				)
			)
		)
		(property "Device Type" "VIA-PCIE-4P-394076"
			(at -3.7211 -6.0325 90)
			(unlocked yes)
			(layer "F.Fab")
			(hide yes)
			(effects
				(font
					(size 1.016 1.016)
					(thickness 0.1524)
				)
			)
		)
		(duplicate_pad_numbers_are_jumpers no)
		(fp_rect
			(start -1.9685 0.381)
			(end 1.9685 -0.381)
			(stroke
				(width 0)
				(type default)
			)
			(fill no)
			(layer "F.CrtYd")
		)
		(fp_rect
			(start -1.9685 0.381)
			(end 1.9685 -0.381)
			(stroke
				(width 0)
				(type default)
			)
			(fill no)
			(layer "F.Fab")
		)
		(pad "1" thru_hole circle
			(at -1.5875 0 90)
			(size 0.508 0.508)
			(drill 0.254)
			(layers "*.Cu" "*.Mask")
			(remove_unused_layers no)
			(net "GND")
			(clearance 0.127)
			(thermal_gap 0.127)
		)
		(pad "2" thru_hole circle
			(at -0.5715 0 90)
			(size 0.508 0.508)
			(drill 0.254)
			(layers "*.Cu" "*.Mask")
			(remove_unused_layers no)
			(net "PHY_SCC_A_TO_DRV_A_6_DP")
			(clearance 0.127)
			(thermal_gap 0.127)
		)
		(pad "3" thru_hole circle
			(at 0.5715 0 90)
			(size 0.508 0.508)
			(drill 0.254)
			(layers "*.Cu" "*.Mask")
			(remove_unused_layers no)
			(net "PHY_SCC_A_TO_DRV_A_6_DN")
			(clearance 0.127)
			(thermal_gap 0.127)
		)
		(pad "4" thru_hole circle
			(at 1.5875 0 90)
			(size 0.508 0.508)
			(drill 0.254)
			(layers "*.Cu" "*.Mask")
			(remove_unused_layers no)
			(net "GND")
			(clearance 0.127)
			(thermal_gap 0.127)
		)
	)
	(footprint ""
		(layer "F.Cu")
		(at 350.066102 -183.620918)
		(property "Reference" "TP97"
			(at 0 0 0)
			(layer "F.SilkS")
			(hide yes)
			(effects
				(font
					(size 1.27 1.27)
				)
			)
		)
		(property "Value" "TPAD32-GP"
			(at -0.0508 -1.6764 0)
			(unlocked yes)
			(layer "F.Fab")
			(hide yes)
			(effects
				(font
					(size 1.016 1.016)
					(thickness 0.1524)
				)
			)
		)
		(property "Device Type" "TPAD32"
			(at -0.0508 -3.2004 0)
			(unlocked yes)
			(layer "F.Fab")
			(hide yes)
			(effects
				(font
					(size 1.016 1.016)
					(thickness 0.1524)
				)
			)
		)
		(duplicate_pad_numbers_are_jumpers no)
		(fp_poly
			(pts
				(arc
					(start 0.4064 0)
					(mid -0.4064 0)
					(end 0.4064 0)
				)
			)
			(stroke
				(width 0)
				(type default)
			)
			(fill no)
			(layer "F.CrtYd")
		)
		(fp_poly
			(pts
				(arc
					(start 0.7112 0)
					(mid -0.7112 0)
					(end 0.7112 0)
				)
			)
			(stroke
				(width 0)
				(type default)
			)
			(fill no)
			(layer "F.Fab")
		)
		(pad "1" smd circle
			(at 0 0)
			(size 0.8128 0.8128)
			(layers "F.Cu" "F.Mask" "F.Paste")
			(net "ACT_HDD_19")
		)
	)
	(footprint ""
		(layer "F.Cu")
		(at 26.325068 -9.19988)
		(property "Reference" ""
			(at 0 0 0)
			(layer "F.SilkS")
			(hide yes)
			(effects
				(font
					(size 1.27 1.27)
				)
			)
		)
		(property "Value" "*"
			(at -6.1214 1.4351 0)
			(unlocked yes)
			(layer "F.Fab")
			(hide yes)
			(effects
				(font
					(size 1.016 1.016)
					(thickness 0.1524)
				)
			)
		)
		(duplicate_pad_numbers_are_jumpers no)
		(fp_poly
			(pts
				(arc
					(start 5.0673 0)
					(mid -5.0673 0)
					(end 5.0673 0)
				)
			)
			(stroke
				(width 0)
				(type default)
			)
			(fill no)
			(layer "B.CrtYd")
		)
		(fp_poly
			(pts
				(arc
					(start 5.0673 0)
					(mid -5.0673 0)
					(end 5.0673 0)
				)
			)
			(stroke
				(width 0)
				(type default)
			)
			(fill no)
			(layer "F.CrtYd")
		)
		(fp_poly
			(pts
				(arc
					(start 5.0673 0)
					(mid -5.0673 0)
					(end 5.0673 0)
				)
			)
			(stroke
				(width 0)
				(type default)
			)
			(fill no)
			(layer "B.Fab")
		)
		(fp_poly
			(pts
				(arc
					(start 5.0673 0)
					(mid -5.0673 0)
					(end 5.0673 0)
				)
			)
			(stroke
				(width 0)
				(type default)
			)
			(fill no)
			(layer "F.Fab")
		)
		(pad "1" thru_hole circle
			(at 0 0)
			(size 9.525 9.525)
			(drill 5.715)
			(layers "*.Cu" "*.Mask")
			(remove_unused_layers no)
			(net "Net_23")
			(clearance -1.397)
			(thermal_gap 0.3048)
			(padstack
				(mode front_inner_back)
				(layer "Inner"
					(shape circle)
					(size 6.1214 6.1214)
					(clearance 0.3048)
				)
				(layer "B.Cu"
					(shape circle)
					(size 9.525 9.525)
					(clearance -1.397)
				)
			)
		)
		(zone
			(layers "F.Cu" "B.Cu" "In1.Cu" "In2.Cu" "In3.Cu" "In4.Cu" "In5.Cu" "In6.Cu"
				"In7.Cu" "In8.Cu" "In9.Cu" "In10.Cu"
			)
			(hatch none 0.5)
			(connect_pads
				(clearance 0)
			)
			(min_thickness 0.25)
			(keepout
				(tracks not_allowed)
				(vias allowed)
				(pads allowed)
				(copperpour not_allowed)
				(footprints allowed)
			)
			(placement
				(enabled no)
				(sheetname "")
			)
			(fill
				(thermal_gap 0.5)
				(thermal_bridge_width 0.5)
				(island_removal_mode 0)
			)
			(polygon
				(pts
					(arc
						(start 31.087568 -9.19988)
						(mid 21.562568 -9.19988)
						(end 31.087568 -9.19988)
					)
				)
			)
		)
	)
	(footprint ""
		(layer "F.Cu")
		(at 22.996398 -276.014942 -90)
		(property "Reference" "R966"
			(at 0 0 270)
			(layer "F.SilkS")
			(hide yes)
			(effects
				(font
					(size 1.27 1.27)
				)
			)
		)
		(property "Value" "1KR2F-3-GP"
			(at 0.064008 -3.993896 270)
			(unlocked yes)
			(layer "F.Fab")
			(hide yes)
			(effects
				(font
					(size 1.016 1.016)
					(thickness 0.1524)
				)
			)
		)
		(property "Device Type" "R402H16"
			(at 0.064008 -5.517896 270)
			(unlocked yes)
			(layer "F.Fab")
			(hide yes)
			(effects
				(font
					(size 1.016 1.016)
					(thickness 0.1524)
				)
			)
		)
		(duplicate_pad_numbers_are_jumpers no)
		(fp_line
			(start -0.508 -0.9398)
			(end -0.508 0.9398)
			(stroke
				(width 0.1524)
				(type default)
			)
			(layer "F.SilkS")
		)
		(fp_line
			(start 0.508 -0.9398)
			(end -0.508 -0.9398)
			(stroke
				(width 0.1524)
				(type default)
			)
			(layer "F.SilkS")
		)
		(fp_rect
			(start -0.508 0.9398)
			(end 0.508 -0.9398)
			(stroke
				(width 0)
				(type default)
			)
			(fill no)
			(layer "F.CrtYd")
		)
		(fp_rect
			(start -0.508 0.9398)
			(end 0.508 -0.9398)
			(stroke
				(width 0)
				(type default)
			)
			(fill no)
			(layer "F.Fab")
		)
		(pad "1" smd custom
			(at 0 -0.4445 270)
			(size 0.1397 0.1397)
			(layers "F.Cu" "F.Mask" "F.Paste")
			(net "P3V3_STBY_A")
			(options
				(clearance outline)
				(anchor circle)
			)
			(primitives
				(gr_poly
					(pts
						(arc
							(start -0.1778 -0.2794)
							(mid -0.249642 -0.249642)
							(end -0.2794 -0.1778)
						)
						(arc
							(start -0.2794 0.1778)
							(mid -0.249642 0.249642)
							(end -0.1778 0.2794)
						)
						(arc
							(start 0.1778 0.2794)
							(mid 0.249642 0.249642)
							(end 0.2794 0.1778)
						)
						(arc
							(start 0.2794 -0.1778)
							(mid 0.249642 -0.249642)
							(end 0.1778 -0.2794)
						)
					)
					(width 0)
					(fill yes)
				)
			)
		)
		(pad "2" smd custom
			(at 0 0.4445 270)
			(size 0.1397 0.1397)
			(layers "F.Cu" "F.Mask" "F.Paste")
			(net "SW_PWR_R_HDD0")
			(options
				(clearance outline)
				(anchor circle)
			)
			(primitives
				(gr_poly
					(pts
						(arc
							(start -0.1778 -0.2794)
							(mid -0.249642 -0.249642)
							(end -0.2794 -0.1778)
						)
						(arc
							(start -0.2794 0.1778)
							(mid -0.249642 0.249642)
							(end -0.1778 0.2794)
						)
						(arc
							(start 0.1778 0.2794)
							(mid 0.249642 0.249642)
							(end 0.2794 0.1778)
						)
						(arc
							(start 0.2794 -0.1778)
							(mid 0.249642 -0.249642)
							(end 0.1778 -0.2794)
						)
					)
					(width 0)
					(fill yes)
				)
			)
		)
	)
	(footprint ""
		(layer "F.Cu")
		(at 434.710078 -127.724662 180)
		(property "Reference" "Q285"
			(at 0 0 180)
			(layer "F.SilkS")
			(hide yes)
			(effects
				(font
					(size 1.27 1.27)
				)
			)
		)
		(property "Value" "SSM3K324R-GP"
			(at 0.127 -8.9662 180)
			(unlocked yes)
			(layer "F.Fab")
			(hide yes)
			(effects
				(font
					(size 1.016 1.016)
					(thickness 0.1524)
				)
			)
		)
		(property "Device Type" "SOT23DGS2D4H35"
			(at 0.127 -10.4902 180)
			(unlocked yes)
			(layer "F.Fab")
			(hide yes)
			(effects
				(font
					(size 1.016 1.016)
					(thickness 0.1524)
				)
			)
		)
		(duplicate_pad_numbers_are_jumpers no)
		(fp_line
			(start 1.651 1.778)
			(end 1.651 -1.778)
			(stroke
				(width 0.1524)
				(type default)
			)
			(layer "F.SilkS")
		)
		(fp_line
			(start 1.651 -1.778)
			(end -1.651 -1.778)
			(stroke
				(width 0.1524)
				(type default)
			)
			(layer "F.SilkS")
		)
		(fp_line
			(start -1.651 1.778)
			(end 1.651 1.778)
			(stroke
				(width 0.1524)
				(type default)
			)
			(layer "F.SilkS")
		)
		(fp_line
			(start -1.651 -1.778)
			(end -1.651 1.778)
			(stroke
				(width 0.1524)
				(type default)
			)
			(layer "F.SilkS")
		)
		(fp_poly
			(pts
				(xy -1.778 1.8796) (xy -1.778 -1.8796) (xy 1.778 -1.8796) (xy 1.778 1.8796)
			)
			(stroke
				(width 0)
				(type default)
			)
			(fill no)
			(layer "F.CrtYd")
		)
		(fp_poly
			(pts
				(xy -1.778 1.8796) (xy -1.778 -1.8796) (xy 1.778 -1.8796) (xy 1.778 1.8796)
			)
			(stroke
				(width 0)
				(type default)
			)
			(fill no)
			(layer "F.Fab")
		)
		(pad "D" smd custom
			(at 0 -0.9525 180)
			(size 0.1905 0.1905)
			(layers "F.Cu" "F.Mask" "F.Paste")
			(net "DRV_ACT_22_N")
			(options
				(clearance outline)
				(anchor circle)
			)
			(primitives
				(gr_poly
					(pts
						(arc
							(start -0.1778 0.5715)
							(mid -0.321484 0.511984)
							(end -0.381 0.3683)
						)
						(arc
							(start -0.381 -0.3683)
							(mid -0.321484 -0.511984)
							(end -0.1778 -0.5715)
						)
						(arc
							(start 0.1778 -0.5715)
							(mid 0.321484 -0.511984)
							(end 0.381 -0.3683)
						)
						(arc
							(start 0.381 0.3683)
							(mid 0.321484 0.511984)
							(end 0.1778 0.5715)
						)
					)
					(width 0)
					(fill yes)
				)
			)
		)
		(pad "G" smd custom
			(at -0.98425 0.9525 180)
			(size 0.1905 0.1905)
			(layers "F.Cu" "F.Mask" "F.Paste")
			(net "DRIVE_A_22_ACT")
			(options
				(clearance outline)
				(anchor circle)
			)
			(primitives
				(gr_poly
					(pts
						(arc
							(start -0.1778 0.5715)
							(mid -0.321484 0.511984)
							(end -0.381 0.3683)
						)
						(arc
							(start -0.381 -0.3683)
							(mid -0.321484 -0.511984)
							(end -0.1778 -0.5715)
						)
						(arc
							(start 0.1778 -0.5715)
							(mid 0.321484 -0.511984)
							(end 0.381 -0.3683)
						)
						(arc
							(start 0.381 0.3683)
							(mid 0.321484 0.511984)
							(end 0.1778 0.5715)
						)
					)
					(width 0)
					(fill yes)
				)
			)
		)
		(pad "S" smd custom
			(at 0.98425 0.9525 180)
			(size 0.1905 0.1905)
			(layers "F.Cu" "F.Mask" "F.Paste")
			(net "GND")
			(options
				(clearance outline)
				(anchor circle)
			)
			(primitives
				(gr_poly
					(pts
						(arc
							(start -0.1778 0.5715)
							(mid -0.321484 0.511984)
							(end -0.381 0.3683)
						)
						(arc
							(start -0.381 -0.3683)
							(mid -0.321484 -0.511984)
							(end -0.1778 -0.5715)
						)
						(arc
							(start 0.1778 -0.5715)
							(mid 0.321484 -0.511984)
							(end 0.381 -0.3683)
						)
						(arc
							(start 0.381 0.3683)
							(mid 0.321484 0.511984)
							(end 0.1778 0.5715)
						)
					)
					(width 0)
					(fill yes)
				)
			)
		)
	)
	(footprint ""
		(layer "F.Cu")
		(at 178.181 -177.778918 -90)
		(property "Reference" "C261"
			(at 0 0 270)
			(layer "F.SilkS")
			(hide yes)
			(effects
				(font
					(size 1.27 1.27)
				)
			)
		)
		(property "Value" "SC1U16V3KX-5GP"
			(at 0 -2.8194 270)
			(unlocked yes)
			(layer "F.Fab")
			(hide yes)
			(effects
				(font
					(size 1.016 1.016)
					(thickness 0.1524)
				)
			)
		)
		(property "Device Type" "C603H36"
			(at 0 -4.3434 270)
			(unlocked yes)
			(layer "F.Fab")
			(hide yes)
			(effects
				(font
					(size 1.016 1.016)
					(thickness 0.1524)
				)
			)
		)
		(duplicate_pad_numbers_are_jumpers no)
		(fp_line
			(start 0.508 0)
			(end -0.508 0)
			(stroke
				(width 0.2032)
				(type default)
			)
			(layer "F.SilkS")
		)
		(fp_rect
			(start -0.5842 1.3335)
			(end 0.5842 -1.3335)
			(stroke
				(width 0)
				(type default)
			)
			(fill no)
			(layer "F.CrtYd")
		)
		(fp_rect
			(start -0.5842 1.3335)
			(end 0.5842 -1.3335)
			(stroke
				(width 0)
				(type default)
			)
			(fill no)
			(layer "F.Fab")
		)
		(pad "1" smd custom
			(at 0 -0.762 270)
			(size 0.2159 0.2159)
			(layers "F.Cu" "F.Mask" "F.Paste")
			(net "P5V_HDD17")
			(options
				(clearance outline)
				(anchor circle)
			)
			(primitives
				(gr_poly
					(pts
						(arc
							(start -0.3302 -0.4318)
							(mid -0.402042 -0.402042)
							(end -0.4318 -0.3302)
						)
						(arc
							(start -0.4318 0.3302)
							(mid -0.402042 0.402042)
							(end -0.3302 0.4318)
						)
						(arc
							(start 0.3302 0.4318)
							(mid 0.402042 0.402042)
							(end 0.4318 0.3302)
						)
						(arc
							(start 0.4318 -0.3302)
							(mid 0.402042 -0.402042)
							(end 0.3302 -0.4318)
						)
					)
					(width 0)
					(fill yes)
				)
			)
		)
		(pad "2" smd custom
			(at 0 0.762 270)
			(size 0.2159 0.2159)
			(layers "F.Cu" "F.Mask" "F.Paste")
			(net "GND")
			(options
				(clearance outline)
				(anchor circle)
			)
			(primitives
				(gr_poly
					(pts
						(arc
							(start -0.3302 -0.4318)
							(mid -0.402042 -0.402042)
							(end -0.4318 -0.3302)
						)
						(arc
							(start -0.4318 0.3302)
							(mid -0.402042 0.402042)
							(end -0.3302 0.4318)
						)
						(arc
							(start 0.3302 0.4318)
							(mid 0.402042 0.402042)
							(end 0.4318 0.3302)
						)
						(arc
							(start 0.4318 -0.3302)
							(mid 0.402042 -0.402042)
							(end 0.3302 -0.4318)
						)
					)
					(width 0)
					(fill yes)
				)
			)
		)
	)
)
